(kicad_pcb
	(version 20260206)
	(generator "pcbnew")
	(generator_version "10.0")
	(general
		(thickness 1.6)
		(legacy_teardrops no)
	)
	(paper "A4")
	(title_block
		(title "Bryce Canyon_F.DPB_16315-1-OCP.brd")
		(comment 1 "Bryce Canyon / footprints 7-12 of 2223")
	)
	(layers
		(0 "F.Cu" signal "TOP")
		(4 "In1.Cu" signal "L2GND")
		(6 "In2.Cu" signal "L3")
		(8 "In3.Cu" signal "L4GND")
		(10 "In4.Cu" signal "L5")
		(12 "In5.Cu" signal "L6VCC")
		(14 "In6.Cu" signal "L7VCC")
		(16 "In7.Cu" signal "L8")
		(18 "In8.Cu" signal "L9GND")
		(20 "In9.Cu" signal "L10")
		(22 "In10.Cu" signal "L11GND")
		(2 "B.Cu" signal "BOTTOM")
		(9 "F.Adhes" user "F.Adhesive")
		(11 "B.Adhes" user "B.Adhesive")
		(13 "F.Paste" user "Package Geometry/Pastemask Top")
		(15 "B.Paste" user "Package Geometry/Pastemask Bottom")
		(5 "F.SilkS" user "Ref Des/Silkscreen Top")
		(7 "B.SilkS" user "Ref Des/Silkscreen Bottom")
		(1 "F.Mask" user "Board Geometry/Soldermask Top")
		(3 "B.Mask" user "Board Geometry/Soldermask Bottom")
		(17 "Dwgs.User" user "User.Drawings")
		(19 "Cmts.User" user "User.Comments")
		(21 "Eco1.User" user "User.Eco1")
		(23 "Eco2.User" user "User.Eco2")
		(25 "Edge.Cuts" user "Board Geometry/Outline")
		(27 "Margin" user)
		(31 "F.CrtYd" user "Package Geometry/Place Bound Top")
		(29 "B.CrtYd" user "Package Geometry/Place Bound Bottom")
		(35 "F.Fab" user "Ref Des/Assembly Top")
		(33 "B.Fab" user "Ref Des/Assembly Bottom")
	)
	(footprint ""
		(layer "F.Cu")
		(at 300.7614 -68.453)
		(property "Reference" "U50"
			(at 0 0 0)
			(layer "F.SilkS")
			(hide yes)
			(effects
				(font
					(size 1.27 1.27)
				)
			)
		)
		(property "Value" "TXS0102QDCURQ1-GP"
			(at 0 -11.1252 0)
			(unlocked yes)
			(layer "F.Fab")
			(hide yes)
			(effects
				(font
					(size 1.016 1.016)
					(thickness 0.1524)
				)
			)
		)
		(property "Device Type" "SSOIC8-4H36"
			(at 0 -12.6492 0)
			(unlocked yes)
			(layer "F.Fab")
			(hide yes)
			(effects
				(font
					(size 1.016 1.016)
					(thickness 0.1524)
				)
			)
		)
		(duplicate_pad_numbers_are_jumpers no)
		(fp_line
			(start -1.2954 0.4572)
			(end -1.2954 2.159)
			(stroke
				(width 0.4064)
				(type default)
			)
			(layer "F.SilkS")
		)
		(fp_line
			(start -1.2573 -2.1844)
			(end 1.2573 -2.1844)
			(stroke
				(width 0.1524)
				(type default)
			)
			(layer "F.SilkS")
		)
		(fp_line
			(start -1.2573 -0.3556)
			(end -1.2192 -0.3556)
			(stroke
				(width 0.1524)
				(type default)
			)
			(layer "F.SilkS")
		)
		(fp_line
			(start -1.2573 2.1844)
			(end -1.2573 -2.1844)
			(stroke
				(width 0.1524)
				(type default)
			)
			(layer "F.SilkS")
		)
		(fp_line
			(start -1.2192 -0.3556)
			(end -0.9017 -0.0381)
			(stroke
				(width 0.1524)
				(type default)
			)
			(layer "F.SilkS")
		)
		(fp_line
			(start -1.2065 0.2667)
			(end -1.27 0.2667)
			(stroke
				(width 0.1524)
				(type default)
			)
			(layer "F.SilkS")
		)
		(fp_line
			(start -0.9017 -0.0381)
			(end -1.2065 0.2667)
			(stroke
				(width 0.1524)
				(type default)
			)
			(layer "F.SilkS")
		)
		(fp_line
			(start 1.2573 -2.1844)
			(end 1.2573 2.1844)
			(stroke
				(width 0.1524)
				(type default)
			)
			(layer "F.SilkS")
		)
		(fp_line
			(start 1.2573 2.1844)
			(end -1.2573 2.1844)
			(stroke
				(width 0.1524)
				(type default)
			)
			(layer "F.SilkS")
		)
		(fp_poly
			(pts
				(xy -1.5113 2.4384) (xy 1.5113 2.4384) (xy 1.5113 -2.4384) (xy -1.5113 -2.4384)
			)
			(stroke
				(width 0)
				(type default)
			)
			(fill no)
			(layer "F.CrtYd")
		)
		(fp_poly
			(pts
				(xy -1.5113 -2.4384) (xy 1.5113 -2.4384) (xy 1.5113 2.4384) (xy -1.5113 2.4384)
			)
			(stroke
				(width 0)
				(type default)
			)
			(fill no)
			(layer "F.Fab")
		)
		(pad "1" smd rect
			(at -0.75057 1.1684)
			(size 0.3048 1.524)
			(layers "F.Cu" "F.Mask" "F.Paste")
			(net "I2C_BMC_B_COMP_B_SDA")
		)
		(pad "2" smd rect
			(at -0.25019 1.1684)
			(size 0.3048 1.524)
			(layers "F.Cu" "F.Mask" "F.Paste")
			(net "GND")
		)
		(pad "3" smd rect
			(at 0.25019 1.1684)
			(size 0.3048 1.524)
			(layers "F.Cu" "F.Mask" "F.Paste")
			(net "P3V3_STBY_B")
		)
		(pad "4" smd rect
			(at 0.75057 1.1684)
			(size 0.3048 1.524)
			(layers "F.Cu" "F.Mask" "F.Paste")
			(net "I2C_BMC_B_COMP_B_SDA_BUF")
		)
		(pad "5" smd rect
			(at 0.75057 -1.1684)
			(size 0.3048 1.524)
			(layers "F.Cu" "F.Mask" "F.Paste")
			(net "I2C_BMC_B_COMP_B_SCL_BUF")
		)
		(pad "6" smd rect
			(at 0.25019 -1.1684)
			(size 0.3048 1.524)
			(layers "F.Cu" "F.Mask" "F.Paste")
			(net "TXS0102_B_OE")
		)
		(pad "7" smd rect
			(at -0.25019 -1.1684)
			(size 0.3048 1.524)
			(layers "F.Cu" "F.Mask" "F.Paste")
			(net "P3V3_STBY_B")
		)
		(pad "8" smd rect
			(at -0.75057 -1.1684)
			(size 0.3048 1.524)
			(layers "F.Cu" "F.Mask" "F.Paste")
			(net "I2C_BMC_B_COMP_B_SCL")
		)
	)
	(footprint ""
		(layer "F.Cu")
		(at 80.900016 -94.400116)
		(property "Reference" "FLED15"
			(at 0 0 0)
			(layer "F.SilkS")
			(hide yes)
			(effects
				(font
					(size 1.27 1.27)
				)
			)
		)
		(property "Value" "LED-BY-19-GP"
			(at -2.132076 1.414018 0)
			(unlocked yes)
			(layer "F.Fab")
			(hide yes)
			(effects
				(font
					(size 1.016 1.016)
					(thickness 0.1524)
				)
			)
		)
		(property "Device Type" "LED-1615-4PH26"
			(at -2.132076 -0.109982 0)
			(unlocked yes)
			(layer "F.Fab")
			(hide yes)
			(effects
				(font
					(size 1.016 1.016)
					(thickness 0.1524)
				)
			)
		)
		(duplicate_pad_numbers_are_jumpers no)
		(fp_line
			(start -1.2954 0.254)
			(end -1.2954 1.6002)
			(stroke
				(width 0.508)
				(type default)
			)
			(layer "F.SilkS")
		)
		(fp_line
			(start -1.2954 1.6002)
			(end 1.2954 1.6002)
			(stroke
				(width 0.508)
				(type default)
			)
			(layer "F.SilkS")
		)
		(fp_line
			(start -1.1176 -1.4224)
			(end 1.1176 -1.4224)
			(stroke
				(width 0.1524)
				(type default)
			)
			(layer "F.SilkS")
		)
		(fp_line
			(start -1.1176 1.4224)
			(end -1.1176 -1.4224)
			(stroke
				(width 0.1524)
				(type default)
			)
			(layer "F.SilkS")
		)
		(fp_line
			(start 1.1176 -1.4224)
			(end 1.1176 1.4224)
			(stroke
				(width 0.1524)
				(type default)
			)
			(layer "F.SilkS")
		)
		(fp_line
			(start 1.1176 1.4224)
			(end -1.1176 1.4224)
			(stroke
				(width 0.1524)
				(type default)
			)
			(layer "F.SilkS")
		)
		(fp_line
			(start 1.2954 1.6002)
			(end 1.2954 0.254)
			(stroke
				(width 0.508)
				(type default)
			)
			(layer "F.SilkS")
		)
		(fp_rect
			(start -0.7493 0.8001)
			(end 0.7493 -0.8001)
			(stroke
				(width 0)
				(type default)
			)
			(fill no)
			(layer "F.CrtYd")
		)
		(fp_poly
			(pts
				(xy -1.3716 1.6764) (xy -1.3716 -1.6764) (xy 1.3716 -1.6764) (xy 1.3716 0.0635) (xy 0.7493 0.0635)
				(xy 0.7493 -0.8001) (xy -0.7493 -0.8001) (xy -0.7493 0.8001) (xy 0.7493 0.8001) (xy 0.7493 0.0762)
				(xy 1.3716 0.0762) (xy 1.3716 1.6764)
			)
			(stroke
				(width 0)
				(type default)
			)
			(fill no)
			(layer "F.CrtYd")
		)
		(fp_rect
			(start -1.3716 1.6764)
			(end 1.3716 -1.6764)
			(stroke
				(width 0)
				(type default)
			)
			(fill no)
			(layer "F.Fab")
		)
		(pad "1" smd rect
			(at 0.50038 -0.73025)
			(size 0.7112 0.8636)
			(layers "F.Cu" "F.Mask" "F.Paste")
			(net "DRV_ACT_14")
		)
		(pad "2" smd rect
			(at -0.50038 -0.73025)
			(size 0.7112 0.8636)
			(layers "F.Cu" "F.Mask" "F.Paste")
			(net "FLT_HDD14")
		)
		(pad "3" smd rect
			(at 0.50038 0.73025)
			(size 0.7112 0.8636)
			(layers "F.Cu" "F.Mask" "F.Paste")
			(net "DRV_ACT_14_N")
		)
		(pad "4" smd rect
			(at -0.50038 0.73025)
			(size 0.7112 0.8636)
			(layers "F.Cu" "F.Mask" "F.Paste")
			(net "FLT_HDD14_N")
		)
	)
	(footprint ""
		(layer "F.Cu")
		(at 264.254742 -221.666562 90)
		(property "Reference" "R408"
			(at 0 0 90)
			(layer "F.SilkS")
			(hide yes)
			(effects
				(font
					(size 1.27 1.27)
				)
			)
		)
		(property "Value" "0R2J-2-GP"
			(at 0.064008 -3.993896 90)
			(unlocked yes)
			(layer "F.Fab")
			(hide yes)
			(effects
				(font
					(size 1.016 1.016)
					(thickness 0.1524)
				)
			)
		)
		(property "Device Type" "R402H16"
			(at 0.064008 -5.517896 90)
			(unlocked yes)
			(layer "F.Fab")
			(hide yes)
			(effects
				(font
					(size 1.016 1.016)
					(thickness 0.1524)
				)
			)
		)
		(duplicate_pad_numbers_are_jumpers no)
		(fp_line
			(start 0.508 -0.9398)
			(end -0.508 -0.9398)
			(stroke
				(width 0.1524)
				(type default)
			)
			(layer "F.SilkS")
		)
		(fp_line
			(start -0.508 -0.9398)
			(end -0.508 0.9398)
			(stroke
				(width 0.1524)
				(type default)
			)
			(layer "F.SilkS")
		)
		(fp_rect
			(start -0.508 0.9398)
			(end 0.508 -0.9398)
			(stroke
				(width 0)
				(type default)
			)
			(fill no)
			(layer "F.CrtYd")
		)
		(fp_rect
			(start -0.508 0.9398)
			(end 0.508 -0.9398)
			(stroke
				(width 0)
				(type default)
			)
			(fill no)
			(layer "F.Fab")
		)
		(pad "1" smd custom
			(at 0 -0.4445 90)
			(size 0.1397 0.1397)
			(layers "F.Cu" "F.Mask" "F.Paste")
			(net "I2C_DPB_A_SDA_BUF")
			(options
				(clearance outline)
				(anchor circle)
			)
			(primitives
				(gr_poly
					(pts
						(arc
							(start -0.1778 -0.2794)
							(mid -0.249642 -0.249642)
							(end -0.2794 -0.1778)
						)
						(arc
							(start -0.2794 0.1778)
							(mid -0.249642 0.249642)
							(end -0.1778 0.2794)
						)
						(arc
							(start 0.1778 0.2794)
							(mid 0.249642 0.249642)
							(end 0.2794 0.1778)
						)
						(arc
							(start 0.2794 -0.1778)
							(mid 0.249642 -0.249642)
							(end 0.1778 -0.2794)
						)
					)
					(width 0)
					(fill yes)
				)
			)
		)
		(pad "2" smd custom
			(at 0 0.4445 90)
			(size 0.1397 0.1397)
			(layers "F.Cu" "F.Mask" "F.Paste")
			(net "I2C_DPB_A_SDA")
			(options
				(clearance outline)
				(anchor circle)
			)
			(primitives
				(gr_poly
					(pts
						(arc
							(start -0.1778 -0.2794)
							(mid -0.249642 -0.249642)
							(end -0.2794 -0.1778)
						)
						(arc
							(start -0.2794 0.1778)
							(mid -0.249642 0.249642)
							(end -0.1778 0.2794)
						)
						(arc
							(start 0.1778 0.2794)
							(mid 0.249642 0.249642)
							(end 0.2794 0.1778)
						)
						(arc
							(start 0.2794 -0.1778)
							(mid 0.249642 -0.249642)
							(end 0.1778 -0.2794)
						)
					)
					(width 0)
					(fill yes)
				)
			)
		)
	)
	(footprint ""
		(layer "F.Cu")
		(at 471.924126 -53.126894 -90)
		(property "Reference" "C503"
			(at 0 0 270)
			(layer "F.SilkS")
			(hide yes)
			(effects
				(font
					(size 1.27 1.27)
				)
			)
		)
		(property "Value" "SCD033U25V2KX-GP"
			(at 1.1811 -2.7051 270)
			(unlocked yes)
			(layer "F.Fab")
			(hide yes)
			(effects
				(font
					(size 1.016 1.016)
					(thickness 0.1524)
				)
			)
		)
		(property "Device Type" "C402H22"
			(at 1.1811 -4.2291 270)
			(unlocked yes)
			(layer "F.Fab")
			(hide yes)
			(effects
				(font
					(size 1.016 1.016)
					(thickness 0.1524)
				)
			)
		)
		(duplicate_pad_numbers_are_jumpers no)
		(fp_rect
			(start -0.4318 0.9525)
			(end 0.4318 -0.9525)
			(stroke
				(width 0)
				(type default)
			)
			(fill no)
			(layer "F.CrtYd")
		)
		(fp_rect
			(start -0.4318 0.9525)
			(end 0.4318 -0.9525)
			(stroke
				(width 0)
				(type default)
			)
			(fill no)
			(layer "F.Fab")
		)
		(pad "1" smd custom
			(at 0 -0.4445 270)
			(size 0.1524 0.1524)
			(layers "F.Cu" "F.Mask" "F.Paste")
			(net "SW_HDD_P35")
			(options
				(clearance outline)
				(anchor circle)
			)
			(primitives
				(gr_poly
					(pts
						(arc
							(start 0.3048 -0.2032)
							(mid 0.275042 -0.275042)
							(end 0.2032 -0.3048)
						)
						(arc
							(start -0.2032 -0.3048)
							(mid -0.275042 -0.275042)
							(end -0.3048 -0.2032)
						)
						(arc
							(start -0.3048 0.2032)
							(mid -0.275042 0.275042)
							(end -0.2032 0.3048)
						)
						(arc
							(start 0.2032 0.3048)
							(mid 0.275042 0.275042)
							(end 0.3048 0.2032)
						)
					)
					(width 0)
					(fill yes)
				)
			)
		)
		(pad "2" smd custom
			(at 0 0.4445 270)
			(size 0.1524 0.1524)
			(layers "F.Cu" "F.Mask" "F.Paste")
			(net "GND")
			(options
				(clearance outline)
				(anchor circle)
			)
			(primitives
				(gr_poly
					(pts
						(arc
							(start 0.3048 -0.2032)
							(mid 0.275042 -0.275042)
							(end 0.2032 -0.3048)
						)
						(arc
							(start -0.2032 -0.3048)
							(mid -0.275042 -0.275042)
							(end -0.3048 -0.2032)
						)
						(arc
							(start -0.3048 0.2032)
							(mid -0.275042 0.275042)
							(end -0.2032 0.3048)
						)
						(arc
							(start 0.2032 0.3048)
							(mid 0.275042 0.275042)
							(end 0.3048 0.2032)
						)
					)
					(width 0)
					(fill yes)
				)
			)
		)
	)
	(footprint ""
		(layer "F.Cu")
		(at 18.415 -127.254)
		(property "Reference" "R277"
			(at 0 0 0)
			(layer "F.SilkS")
			(hide yes)
			(effects
				(font
					(size 1.27 1.27)
				)
			)
		)
		(property "Value" "91R3F-1-GP"
			(at -0.0254 -2.5146 0)
			(unlocked yes)
			(layer "F.Fab")
			(hide yes)
			(effects
				(font
					(size 1.016 1.016)
					(thickness 0.1524)
				)
			)
		)
		(property "Device Type" "R603H22"
			(at -0.0254 -4.0386 0)
			(unlocked yes)
			(layer "F.Fab")
			(hide yes)
			(effects
				(font
					(size 1.016 1.016)
					(thickness 0.1524)
				)
			)
		)
		(duplicate_pad_numbers_are_jumpers no)
		(fp_line
			(start -0.4826 0)
			(end -0.2032 0)
			(stroke
				(width 0.2032)
				(type default)
			)
			(layer "F.SilkS")
		)
		(fp_line
			(start 0.2032 0)
			(end 0.4826 0)
			(stroke
				(width 0.2032)
				(type default)
			)
			(layer "F.SilkS")
		)
		(fp_rect
			(start -0.5842 1.3335)
			(end 0.5842 -1.3335)
			(stroke
				(width 0)
				(type default)
			)
			(fill no)
			(layer "F.CrtYd")
		)
		(fp_rect
			(start -0.5842 1.3335)
			(end 0.5842 -1.3335)
			(stroke
				(width 0)
				(type default)
			)
			(fill no)
			(layer "F.Fab")
		)
		(pad "1" smd custom
			(at 0 -0.762)
			(size 0.2159 0.2159)
			(layers "F.Cu" "F.Mask" "F.Paste")
			(net "P5V_A_1")
			(options
				(clearance outline)
				(anchor circle)
			)
			(primitives
				(gr_poly
					(pts
						(arc
							(start -0.3302 -0.4318)
							(mid -0.402042 -0.402042)
							(end -0.4318 -0.3302)
						)
						(arc
							(start -0.4318 0.3302)
							(mid -0.402042 0.402042)
							(end -0.3302 0.4318)
						)
						(arc
							(start 0.3302 0.4318)
							(mid 0.402042 0.402042)
							(end 0.4318 0.3302)
						)
						(arc
							(start 0.4318 -0.3302)
							(mid 0.402042 -0.402042)
							(end 0.3302 -0.4318)
						)
					)
					(width 0)
					(fill yes)
				)
			)
		)
		(pad "2" smd custom
			(at 0 0.762)
			(size 0.2159 0.2159)
			(layers "F.Cu" "F.Mask" "F.Paste")
			(net "DRV_ACT_12")
			(options
				(clearance outline)
				(anchor circle)
			)
			(primitives
				(gr_poly
					(pts
						(arc
							(start -0.3302 -0.4318)
							(mid -0.402042 -0.402042)
							(end -0.4318 -0.3302)
						)
						(arc
							(start -0.4318 0.3302)
							(mid -0.402042 0.402042)
							(end -0.3302 0.4318)
						)
						(arc
							(start 0.3302 0.4318)
							(mid 0.402042 0.402042)
							(end 0.4318 0.3302)
						)
						(arc
							(start 0.4318 -0.3302)
							(mid 0.402042 -0.402042)
							(end 0.3302 -0.4318)
						)
					)
					(width 0)
					(fill yes)
				)
			)
		)
	)
	(footprint ""
		(layer "F.Cu")
		(at 427.390052 -163.554918 -90)
		(property "Reference" "R620"
			(at 0 0 270)
			(layer "F.SilkS")
			(hide yes)
			(effects
				(font
					(size 1.27 1.27)
				)
			)
		)
		(property "Value" "4K7R2J-2-GP"
			(at 0.064008 -3.993896 270)
			(unlocked yes)
			(layer "F.Fab")
			(hide yes)
			(effects
				(font
					(size 1.016 1.016)
					(thickness 0.1524)
				)
			)
		)
		(property "Device Type" "R402H16"
			(at 0.064008 -5.517896 270)
			(unlocked yes)
			(layer "F.Fab")
			(hide yes)
			(effects
				(font
					(size 1.016 1.016)
					(thickness 0.1524)
				)
			)
		)
		(duplicate_pad_numbers_are_jumpers no)
		(fp_line
			(start -0.508 -0.9398)
			(end -0.508 0.9398)
			(stroke
				(width 0.1524)
				(type default)
			)
			(layer "F.SilkS")
		)
		(fp_line
			(start 0.508 -0.9398)
			(end -0.508 -0.9398)
			(stroke
				(width 0.1524)
				(type default)
			)
			(layer "F.SilkS")
		)
		(fp_rect
			(start -0.508 0.9398)
			(end 0.508 -0.9398)
			(stroke
				(width 0)
				(type default)
			)
			(fill no)
			(layer "F.CrtYd")
		)
		(fp_rect
			(start -0.508 0.9398)
			(end 0.508 -0.9398)
			(stroke
				(width 0)
				(type default)
			)
			(fill no)
			(layer "F.Fab")
		)
		(pad "1" smd custom
			(at 0 -0.4445 270)
			(size 0.1397 0.1397)
			(layers "F.Cu" "F.Mask" "F.Paste")
			(net "P12V_A")
			(options
				(clearance outline)
				(anchor circle)
			)
			(primitives
				(gr_poly
					(pts
						(arc
							(start -0.1778 -0.2794)
							(mid -0.249642 -0.249642)
							(end -0.2794 -0.1778)
						)
						(arc
							(start -0.2794 0.1778)
							(mid -0.249642 0.249642)
							(end -0.1778 0.2794)
						)
						(arc
							(start 0.1778 0.2794)
							(mid 0.249642 0.249642)
							(end 0.2794 0.1778)
						)
						(arc
							(start 0.2794 -0.1778)
							(mid 0.249642 -0.249642)
							(end 0.1778 -0.2794)
						)
					)
					(width 0)
					(fill yes)
				)
			)
		)
		(pad "2" smd custom
			(at 0 0.4445 270)
			(size 0.1397 0.1397)
			(layers "F.Cu" "F.Mask" "F.Paste")
			(net "SW_HDD_P21")
			(options
				(clearance outline)
				(anchor circle)
			)
			(primitives
				(gr_poly
					(pts
						(arc
							(start -0.1778 -0.2794)
							(mid -0.249642 -0.249642)
							(end -0.2794 -0.1778)
						)
						(arc
							(start -0.2794 0.1778)
							(mid -0.249642 0.249642)
							(end -0.1778 0.2794)
						)
						(arc
							(start 0.1778 0.2794)
							(mid 0.249642 0.249642)
							(end 0.2794 0.1778)
						)
						(arc
							(start 0.2794 -0.1778)
							(mid 0.249642 -0.249642)
							(end 0.1778 -0.2794)
						)
					)
					(width 0)
					(fill yes)
				)
			)
		)
	)
)
